FILE_TYPE = CONNECTIVITY;
{Allegro Design Entry HDL 17.2-2016 S081 (4005846) 1/11/2022}
"PAGE_NUMBER" = 39;
0"NC";
1"M_C_CPU1_SA_DQ<31:0>";
2"M_C_CPU1_SB_DQ<31:0>";
3"M_C_CPU1_SA_CB<7:0>";
4"M_C_CPU1_SB_CB<7:0>";
5"M_C_CPU1_SA_DQS_DP<9:0>";
6"M_C_CPU1_SB_DQS_DP<9:0>";
7"M_C_CPU1_SA_CA<6:0>";
8"M_C_CPU1_SB_CA<6:0>";
9"M_C_CPU1_SA_DQS_DN<9:0>";
10"M_C_CPU1_SB_DQS_DN<9:0>";
11"M_C_CPU1_ALERT_N";
12"TP_M_C_CPU1_SA_TEST39C";
13"M_C_CPU1_ALERT_R_N";
14"M_C_CPU1_CLK_DN<0>";
15"M_C_CPU1_CLK_DP<0>";
16"M_C_CPU1_SA_CS_N<1>";
17"M_C_CPU1_SA_CS_N<0>";
18"M_C_CPU1_SA_RSP<0>";
19"M_C_CPU1_SA_PAR";
20"M_C_CPU1_SB_CS_N<0>";
21"M_C_CPU1_SB_CS_N<1>";
22"M_C_CPU1_SB_RSP<0>";
23"M_C_CPU1_SB_PAR";
24"M_C_CPU1_RESET_N";
25"M_C_CPU1_SB_CA<6>";
26"M_C_CPU1_SB_DQS_DN<9>";
27"M_C_CPU1_SA_CA<6>";
28"M_C_CPU1_SB_CA<5>";
29"M_C_CPU1_SA_CA<5>";
30"M_C_CPU1_SB_CA<4>";
31"M_C_CPU1_SA_CA<4>";
32"M_C_CPU1_SB_CA<3>";
33"M_C_CPU1_SA_CA<3>";
34"M_C_CPU1_SB_CA<2>";
35"M_C_CPU1_SA_CA<2>";
36"M_C_CPU1_SB_CA<1>";
37"M_C_CPU1_SA_CA<1>";
38"M_C_CPU1_SB_CA<0>";
39"M_C_CPU1_SA_CA<0>";
40"M_C_CPU1_SB_DQS_DP<9>";
41"M_C_CPU1_SB_DQS_DP<7>";
42"M_C_CPU1_SB_DQS_DP<6>";
43"M_C_CPU1_SB_DQS_DP<5>";
44"M_C_CPU1_SB_DQS_DP<4>";
45"M_C_CPU1_SB_DQS_DN<8>";
46"M_C_CPU1_SB_DQS_DP<3>";
47"M_C_CPU1_SB_DQS_DN<7>";
48"M_C_CPU1_SB_DQS_DP<2>";
49"M_C_CPU1_SB_DQS_DN<6>";
50"M_C_CPU1_SB_DQS_DP<1>";
51"M_C_CPU1_SB_DQS_DN<5>";
52"M_C_CPU1_SB_DQS_DP<0>";
53"M_C_CPU1_SB_DQS_DN<4>";
54"M_C_CPU1_SA_DQS_DN<9>";
55"M_C_CPU1_SB_DQS_DN<3>";
56"M_C_CPU1_SB_DQS_DN<2>";
57"M_C_CPU1_SB_DQS_DN<1>";
58"M_C_CPU1_SB_DQS_DN<0>";
59"M_C_CPU1_SB_DQS_DP<8>";
60"M_C_CPU1_SA_DQS_DN<0>";
61"M_C_CPU1_SA_DQS_DP<9>";
62"M_C_CPU1_SA_DQS_DP<8>";
63"M_C_CPU1_SA_DQS_DP<7>";
64"M_C_CPU1_SA_DQS_DP<6>";
65"M_C_CPU1_SA_DQS_DP<5>";
66"M_C_CPU1_SA_DQS_DP<4>";
67"M_C_CPU1_SA_DQS_DN<8>";
68"M_C_CPU1_SA_DQS_DP<3>";
69"M_C_CPU1_SA_DQS_DN<7>";
70"M_C_CPU1_SA_DQS_DP<2>";
71"M_C_CPU1_SA_DQS_DN<6>";
72"M_C_CPU1_SA_DQS_DP<1>";
73"M_C_CPU1_SA_DQS_DN<5>";
74"M_C_CPU1_SA_DQS_DP<0>";
75"M_C_CPU1_SA_DQS_DN<4>";
76"M_C_CPU1_SA_DQS_DN<3>";
77"M_C_CPU1_SA_DQS_DN<2>";
78"M_C_CPU1_SA_DQS_DN<1>";
79"M_C_CPU1_SB_CB<7>";
80"M_C_CPU1_SB_CB<6>";
81"M_C_CPU1_SB_CB<5>";
82"M_C_CPU1_SB_CB<4>";
83"M_C_CPU1_SB_CB<3>";
84"M_C_CPU1_SB_CB<2>";
85"M_C_CPU1_SB_CB<1>";
86"M_C_CPU1_SB_CB<0>";
87"M_C_CPU1_SA_CB<4>";
88"M_C_CPU1_SA_CB<3>";
89"M_C_CPU1_SA_CB<2>";
90"M_C_CPU1_SA_CB<1>";
91"M_C_CPU1_SA_CB<0>";
92"M_C_CPU1_SB_DQ<29>";
93"M_C_CPU1_SB_DQ<28>";
94"M_C_CPU1_SB_DQ<27>";
95"M_C_CPU1_SB_DQ<26>";
96"M_C_CPU1_SB_DQ<25>";
97"M_C_CPU1_SB_DQ<24>";
98"M_C_CPU1_SB_DQ<23>";
99"M_C_CPU1_SB_DQ<22>";
100"M_C_CPU1_SA_CB<7>";
101"M_C_CPU1_SA_CB<6>";
102"M_C_CPU1_SB_DQ<31>";
103"M_C_CPU1_SA_CB<5>";
104"M_C_CPU1_SB_DQ<30>";
105"M_C_CPU1_SB_DQ<7>";
106"M_C_CPU1_SB_DQ<6>";
107"M_C_CPU1_SB_DQ<5>";
108"M_C_CPU1_SB_DQ<4>";
109"M_C_CPU1_SB_DQ<19>";
110"M_C_CPU1_SB_DQ<18>";
111"M_C_CPU1_SB_DQ<17>";
112"M_C_CPU1_SB_DQ<16>";
113"M_C_CPU1_SB_DQ<15>";
114"M_C_CPU1_SB_DQ<14>";
115"M_C_CPU1_SB_DQ<13>";
116"M_C_CPU1_SB_DQ<12>";
117"M_C_CPU1_SB_DQ<11>";
118"M_C_CPU1_SB_DQ<10>";
119"M_C_CPU1_SB_DQ<21>";
120"M_C_CPU1_SB_DQ<9>";
121"M_C_CPU1_SB_DQ<20>";
122"M_C_CPU1_SB_DQ<8>";
123"M_C_CPU1_SA_DQ<24>";
124"M_C_CPU1_SA_DQ<23>";
125"M_C_CPU1_SA_DQ<22>";
126"M_C_CPU1_SA_DQ<21>";
127"M_C_CPU1_SA_DQ<20>";
128"M_C_CPU1_SA_DQ<31>";
129"M_C_CPU1_SB_DQ<3>";
130"M_C_CPU1_SA_DQ<30>";
131"M_C_CPU1_SB_DQ<2>";
132"M_C_CPU1_SB_DQ<1>";
133"M_C_CPU1_SB_DQ<0>";
134"M_C_CPU1_SA_DQ<19>";
135"M_C_CPU1_SA_DQ<18>";
136"M_C_CPU1_SA_DQ<29>";
137"M_C_CPU1_SA_DQ<17>";
138"M_C_CPU1_SA_DQ<28>";
139"M_C_CPU1_SA_DQ<27>";
140"M_C_CPU1_SA_DQ<26>";
141"M_C_CPU1_SA_DQ<25>";
142"M_C_CPU1_SA_DQ<8>";
143"M_C_CPU1_SA_DQ<13>";
144"M_C_CPU1_SA_DQ<7>";
145"M_C_CPU1_SA_DQ<12>";
146"M_C_CPU1_SA_DQ<6>";
147"M_C_CPU1_SA_DQ<11>";
148"M_C_CPU1_SA_DQ<5>";
149"M_C_CPU1_SA_DQ<10>";
150"M_C_CPU1_SA_DQ<4>";
151"M_C_CPU1_SA_DQ<3>";
152"M_C_CPU1_SA_DQ<2>";
153"M_C_CPU1_SA_DQ<1>";
154"M_C_CPU1_SA_DQ<0>";
155"M_C_CPU1_SA_DQ<16>";
156"M_C_CPU1_SA_DQ<15>";
157"M_C_CPU1_SA_DQ<9>";
158"M_C_CPU1_SA_DQ<14>";
%"GENOA_SP5"
"3","(-4750,3675)","0","pure_quanta","I159";
;
LOCATION"U26"
$SEC"3"
CDS_SEC"3"
PART_TYPE"SMLF"
MATERIAL"IO"
VALUE"SOCKET6096_13568-001"
PART_NUMBER"DGA^6000030"
CDS_LIB"pure_quanta"
CDS_LMAN_SYM_OUTLINE"-650,2525,650,-2525"
NEEDS_NO_SIZE"TRUE";
"TEST39C"
$PN"BF55"12;
"MC1_CLK_L"
$PN"BG57"0;
"MC1_CLK_H"
$PN"BF56"0;
"MC0_CLK_L"
$PN"BD56"14;
"MC0_CLK_H"
$PN"BC57"15;
"MCB_PAR"
$PN"BL57"23;
"MCA_PAR"
$PN"BC55"19;
"MCB_DQS_H9"
$PN"BV56"40;
"MCA_CHECK4"
$PN"AN57"87;
"MCA_DATA8"
$PN"L57"142;
"MCA_DATA13"
$PN"T55"143;
"MCA_DATA24"
$PN"AC57"123;
"MCA_DQS_L0"
$PN"H56"60;
"MCB0_CS_L0"
$PN"BM55"20;
"MCB1_CS_L0"
$PN"BL55"0;
"MCB_DATA7"
$PN"CH55"105;
"MCB_DQS_H7"
$PN"CV55"41;
"MCA_CHECK3"
$PN"AL55"88;
"MCA_DATA7"
$PN"L55"144;
"MCA_DATA12"
$PN"R57"145;
"MCA_DATA23"
$PN"AC55"124;
"MCB_DATA6"
$PN"CG57"106;
"MCB_DQS_H6"
$PN"CM55"42;
"MCA_CHECK2"
$PN"AK56"89;
"MCA_DATA6"
$PN"K56"146;
"MCA_DATA11"
$PN"N55"147;
"MCA_DATA22"
$PN"AB56"125;
"MCB_CA6"
$PN"BK56"25;
"MCB_DATA5"
$PN"CG55"107;
"MCB_DQS_H5"
$PN"CF55"43;
"MCB_DQS_L9"
$PN"BW57"26;
"MCA_CA6"
$PN"BB55"27;
"MCA_CHECK1"
$PN"AK55"90;
"MCA_DATA5"
$PN"K55"148;
"MCA_DATA10"
$PN"M56"149;
"MCA_DATA21"
$PN"AB55"126;
"MCB_CA5"
$PN"BK55"28;
"MCB_DATA4"
$PN"CF56"108;
"MCB_DQS_H4"
$PN"BY55"44;
"MCB_DQS_L8"
$PN"DC55"45;
"MCA_CA5"
$PN"BB56"29;
"MCA_CHECK0"
$PN"AJ57"91;
"MCA_DATA4"
$PN"J57"150;
"MCA_DATA20"
$PN"AA57"127;
"MCA_DATA31"
$PN"AJ55"128;
"MCA_DQS_H9"
$PN"AN55"61;
"MCB_CA4"
$PN"BJ55"30;
"MCB_DATA3"
$PN"CD55"129;
"MCB_DQS_H3"
$PN"DB56"46;
"MCB_DQS_L7"
$PN"CU55"47;
"MCA1_CS_L1"
$PN"AV55"0;
"MCA_CA4"
$PN"BA57"31;
"MCA_DATA3"
$PN"G55"151;
"MCA_DATA30"
$PN"AH56"130;
"MCA_DQS_H8"
$PN"AG55"62;
"MCB_CA3"
$PN"BJ57"32;
"MCB_DATA2"
$PN"CC57"131;
"MCB_DATA19"
$PN"CT55"109;
"MCB_DQS_H2"
$PN"CT56"48;
"MCB_DQS_L6"
$PN"CL55"49;
"MCA0_CS_L1"
$PN"AW55"16;
"MCA1_CS_L0"
$PN"AU57"0;
"MCA_CA3"
$PN"BA55"33;
"MCA_DATA2"
$PN"F56"152;
"MCA_DQS_H7"
$PN"AA55"63;
"MCB_CA2"
$PN"BH56"34;
"MCB_DATA1"
$PN"CC55"132;
"MCB_DATA18"
$PN"CR57"110;
"MCB_DATA29"
$PN"DE55"92;
"MCB_DQS_H1"
$PN"CK56"50;
"MCB_DQS_L5"
$PN"CE55"51;
"MCA0_CS_L0"
$PN"AV56"17;
"MCA_CA2"
$PN"AY55"35;
"MCA_DATA1"
$PN"F55"153;
"MCA_DQS_H6"
$PN"R55"64;
"MCB_CA1"
$PN"BH55"36;
"MCB_DATA0"
$PN"CB56"133;
"MCB_DATA17"
$PN"CR55"111;
"MCB_DATA28"
$PN"DD56"93;
"MCB_DQS_H0"
$PN"CD56"52;
"MCB_DQS_L4"
$PN"BW55"53;
"MCA_CA1"
$PN"AY56"37;
"MCA_DATA0"
$PN"E57"154;
"MCA_DQS_H5"
$PN"J55"65;
"MCA_DQS_L9"
$PN"AM55"54;
"MCB0_RSP_L"
$PN"BP56"22;
"MCB1_RSP_L"
$PN"BR57"0;
"MCB_CA0"
$PN"BG55"38;
"MCB_CHECK7"
$PN"BV55"79;
"MCB_DATA16"
$PN"CP56"112;
"MCB_DATA27"
$PN"DB55"94;
"MCB_DQS_L3"
$PN"DC57"55;
"MCA_CA0"
$PN"AW57"39;
"MCA_DQS_H4"
$PN"AL57"66;
"MCA_DQS_L8"
$PN"AF55"67;
"MCB_CHECK6"
$PN"BU57"80;
"MCB_DATA15"
$PN"CP55"113;
"MCB_DATA26"
$PN"DA57"95;
"MCB_DQS_L2"
$PN"CU57"56;
"MCA_DQS_H3"
$PN"AE57"68;
"MCA_DQS_L7"
$PN"Y55"69;
"MCB_CHECK5"
$PN"BU55"81;
"MCB_DATA14"
$PN"CN57"114;
"MCB_DATA25"
$PN"DA55"96;
"MCB_DQS_L1"
$PN"CL57"57;
"MCA_DATA19"
$PN"W55"134;
"MCA_DQS_H2"
$PN"W57"70;
"MCA_DQS_L6"
$PN"P55"71;
"MCB_CHECK4"
$PN"BT56"82;
"MCB_DATA13"
$PN"CN55"115;
"MCB_DATA24"
$PN"CY56"97;
"MCB_DQS_L0"
$PN"CE57"58;
"MCA_DATA18"
$PN"V56"135;
"MCA_DATA29"
$PN"AH55"136;
"MCA_DQS_H1"
$PN"N57"72;
"MCA_DQS_L5"
$PN"H55"73;
"MCB_CHECK3"
$PN"CB55"83;
"MCB_DATA12"
$PN"CM56"116;
"MCB_DATA23"
$PN"CY55"98;
"MCA_DATA17"
$PN"V55"137;
"MCA_DATA28"
$PN"AG57"138;
"MCA_DQS_H0"
$PN"G57"74;
"MCA_DQS_L4"
$PN"AM56"75;
"MCB_CHECK2"
$PN"CA57"84;
"MCB_DATA11"
$PN"CK55"117;
"MCB_DATA22"
$PN"CW57"99;
"MCA1_RSP_L"
$PN"BP55"0;
"MCA_CHECK7"
$PN"AR55"100;
"MCA_DATA16"
$PN"U57"155;
"MCA_DATA27"
$PN"AE55"139;
"MCA_DQS_L3"
$PN"AF56"76;
"MCB_CHECK1"
$PN"CA55"85;
"MCB_DATA10"
$PN"CJ57"118;
"MCB_DATA21"
$PN"CW55"119;
"MCA0_RSP_L"
$PN"BN55"18;
"MCA_CHECK6"
$PN"AP56"101;
"MCA_DATA15"
$PN"U55"156;
"MCA_DATA26"
$PN"AD56"140;
"MCA_DQS_L2"
$PN"Y56"77;
"MCB_CHECK0"
$PN"BY56"86;
"MCB_DATA9"
$PN"CJ55"120;
"MCB_DATA20"
$PN"CV56"121;
"MCB_DATA31"
$PN"DF55"102;
"MCA_CHECK5"
$PN"AP55"103;
"MCA_DATA9"
$PN"M55"157;
"MCA_DATA14"
$PN"T56"158;
"MCA_DATA25"
$PN"AD55"141;
"MCA_DQS_L1"
$PN"P56"78;
"MCB0_CS_L1"
$PN"BN57"21;
"MCB1_CS_L1"
$PN"BM56"0;
"MCB_DATA8"
$PN"CH56"122;
"MCB_DATA30"
$PN"DE57"104;
"MCB_DQS_H8"
$PN"DD55"59;
"MC_RESET_L"
$PN"AU55"24;
"MC_ALERT_L"
$PN"AT55"13;
%"TAP"
"1","(-3475,6050)","0","mstr_standard","I162";
;
CDS_LIB"mstr_standard"
BODY_TYPE"PLUMBING"
HDL_TAP"TRUE";
"B \NAC \NWC"1;
"S \NAC"
BN"0"154;
%"TAP"
"1","(-3475,6000)","0","mstr_standard","I163";
;
CDS_LIB"mstr_standard"
BODY_TYPE"PLUMBING"
HDL_TAP"TRUE";
"B \NAC \NWC"1;
"S \NAC"
BN"1"153;
%"TAP"
"1","(-3475,5900)","0","mstr_standard","I164";
;
CDS_LIB"mstr_standard"
BODY_TYPE"PLUMBING"
HDL_TAP"TRUE";
"B \NAC \NWC"1;
"S \NAC"
BN"3"151;
%"TAP"
"1","(-3475,5950)","0","mstr_standard","I165";
;
CDS_LIB"mstr_standard"
BODY_TYPE"PLUMBING"
HDL_TAP"TRUE";
"B \NAC \NWC"1;
"S \NAC"
BN"2"152;
%"TAP"
"1","(-3475,5750)","0","mstr_standard","I166";
;
CDS_LIB"mstr_standard"
BODY_TYPE"PLUMBING"
HDL_TAP"TRUE";
"B \NAC \NWC"1;
"S \NAC"
BN"6"146;
%"TAP"
"1","(-3475,5800)","0","mstr_standard","I167";
;
CDS_LIB"mstr_standard"
BODY_TYPE"PLUMBING"
HDL_TAP"TRUE";
"B \NAC \NWC"1;
"S \NAC"
BN"5"148;
%"TAP"
"1","(-3475,5850)","0","mstr_standard","I168";
;
CDS_LIB"mstr_standard"
BODY_TYPE"PLUMBING"
HDL_TAP"TRUE";
"B \NAC \NWC"1;
"S \NAC"
BN"4"150;
%"TAP"
"1","(-3475,5700)","0","mstr_standard","I169";
;
CDS_LIB"mstr_standard"
BODY_TYPE"PLUMBING"
HDL_TAP"TRUE";
"B \NAC \NWC"1;
"S \NAC"
BN"7"144;
%"TAP"
"1","(-3475,5550)","0","mstr_standard","I170";
;
CDS_LIB"mstr_standard"
BODY_TYPE"PLUMBING"
HDL_TAP"TRUE";
"B \NAC \NWC"1;
"S \NAC"
BN"9"157;
%"TAP"
"1","(-3475,5600)","0","mstr_standard","I171";
;
CDS_LIB"mstr_standard"
BODY_TYPE"PLUMBING"
HDL_TAP"TRUE";
"B \NAC \NWC"1;
"S \NAC"
BN"8"142;
%"TAP"
"1","(-3475,5500)","0","mstr_standard","I172";
;
CDS_LIB"mstr_standard"
BODY_TYPE"PLUMBING"
HDL_TAP"TRUE";
"B \NAC \NWC"1;
"S \NAC"
BN"10"149;
%"TAP"
"1","(-3475,5400)","0","mstr_standard","I173";
;
CDS_LIB"mstr_standard"
BODY_TYPE"PLUMBING"
HDL_TAP"TRUE";
"B \NAC \NWC"1;
"S \NAC"
BN"12"145;
%"TAP"
"1","(-3475,5450)","0","mstr_standard","I174";
;
CDS_LIB"mstr_standard"
BODY_TYPE"PLUMBING"
HDL_TAP"TRUE";
"B \NAC \NWC"1;
"S \NAC"
BN"11"147;
%"TAP"
"1","(-3475,5350)","0","mstr_standard","I175";
;
CDS_LIB"mstr_standard"
BODY_TYPE"PLUMBING"
HDL_TAP"TRUE";
"B \NAC \NWC"1;
"S \NAC"
BN"13"143;
%"TAP"
"1","(-3475,5300)","0","mstr_standard","I176";
;
CDS_LIB"mstr_standard"
BODY_TYPE"PLUMBING"
HDL_TAP"TRUE";
"B \NAC \NWC"1;
"S \NAC"
BN"14"158;
%"TAP"
"1","(-3475,5250)","0","mstr_standard","I177";
;
CDS_LIB"mstr_standard"
BODY_TYPE"PLUMBING"
HDL_TAP"TRUE";
"B \NAC \NWC"1;
"S \NAC"
BN"15"156;
%"TAP"
"1","(-3475,5150)","0","mstr_standard","I178";
;
CDS_LIB"mstr_standard"
BODY_TYPE"PLUMBING"
HDL_TAP"TRUE";
"B \NAC \NWC"1;
"S \NAC"
BN"16"155;
%"TAP"
"1","(-3475,5000)","0","mstr_standard","I179";
;
CDS_LIB"mstr_standard"
BODY_TYPE"PLUMBING"
HDL_TAP"TRUE";
"B \NAC \NWC"1;
"S \NAC"
BN"19"134;
%"TAP"
"1","(-3475,5050)","0","mstr_standard","I180";
;
CDS_LIB"mstr_standard"
BODY_TYPE"PLUMBING"
HDL_TAP"TRUE";
"B \NAC \NWC"1;
"S \NAC"
BN"18"135;
%"TAP"
"1","(-3475,5100)","0","mstr_standard","I181";
;
CDS_LIB"mstr_standard"
BODY_TYPE"PLUMBING"
HDL_TAP"TRUE";
"B \NAC \NWC"1;
"S \NAC"
BN"17"137;
%"TAP"
"1","(-3475,4900)","0","mstr_standard","I182";
;
CDS_LIB"mstr_standard"
BODY_TYPE"PLUMBING"
HDL_TAP"TRUE";
"B \NAC \NWC"1;
"S \NAC"
BN"21"126;
%"TAP"
"1","(-3475,4950)","0","mstr_standard","I183";
;
CDS_LIB"mstr_standard"
BODY_TYPE"PLUMBING"
HDL_TAP"TRUE";
"B \NAC \NWC"1;
"S \NAC"
BN"20"127;
%"TAP"
"1","(-3475,4800)","0","mstr_standard","I184";
;
CDS_LIB"mstr_standard"
BODY_TYPE"PLUMBING"
HDL_TAP"TRUE";
"B \NAC \NWC"1;
"S \NAC"
BN"23"124;
%"TAP"
"1","(-3475,4850)","0","mstr_standard","I185";
;
CDS_LIB"mstr_standard"
BODY_TYPE"PLUMBING"
HDL_TAP"TRUE";
"B \NAC \NWC"1;
"S \NAC"
BN"22"125;
%"TAP"
"1","(-3475,4650)","0","mstr_standard","I186";
;
CDS_LIB"mstr_standard"
BODY_TYPE"PLUMBING"
HDL_TAP"TRUE";
"B \NAC \NWC"1;
"S \NAC"
BN"25"141;
%"TAP"
"1","(-3475,4700)","0","mstr_standard","I187";
;
CDS_LIB"mstr_standard"
BODY_TYPE"PLUMBING"
HDL_TAP"TRUE";
"B \NAC \NWC"1;
"S \NAC"
BN"24"123;
%"TAP"
"1","(-3475,4600)","0","mstr_standard","I188";
;
CDS_LIB"mstr_standard"
BODY_TYPE"PLUMBING"
HDL_TAP"TRUE";
"B \NAC \NWC"1;
"S \NAC"
BN"26"140;
%"TAP"
"1","(-3475,4500)","0","mstr_standard","I189";
;
CDS_LIB"mstr_standard"
BODY_TYPE"PLUMBING"
HDL_TAP"TRUE";
"B \NAC \NWC"1;
"S \NAC"
BN"28"138;
%"TAP"
"1","(-3475,4550)","0","mstr_standard","I190";
;
CDS_LIB"mstr_standard"
BODY_TYPE"PLUMBING"
HDL_TAP"TRUE";
"B \NAC \NWC"1;
"S \NAC"
BN"27"139;
%"TAP"
"1","(-3475,4400)","0","mstr_standard","I191";
;
CDS_LIB"mstr_standard"
BODY_TYPE"PLUMBING"
HDL_TAP"TRUE";
"B \NAC \NWC"1;
"S \NAC"
BN"30"130;
%"TAP"
"1","(-3475,4450)","0","mstr_standard","I192";
;
CDS_LIB"mstr_standard"
BODY_TYPE"PLUMBING"
HDL_TAP"TRUE";
"B \NAC \NWC"1;
"S \NAC"
BN"29"136;
%"TAP"
"1","(-3475,4350)","0","mstr_standard","I193";
;
CDS_LIB"mstr_standard"
BODY_TYPE"PLUMBING"
HDL_TAP"TRUE";
"B \NAC \NWC"1;
"S \NAC"
BN"31"128;
%"TAP"
"1","(-3475,4250)","0","mstr_standard","I194";
;
CDS_LIB"mstr_standard"
BODY_TYPE"PLUMBING"
HDL_TAP"TRUE";
"B \NAC \NWC"2;
"S \NAC"
BN"0"133;
%"TAP"
"1","(-3475,4200)","0","mstr_standard","I195";
;
CDS_LIB"mstr_standard"
BODY_TYPE"PLUMBING"
HDL_TAP"TRUE";
"B \NAC \NWC"2;
"S \NAC"
BN"1"132;
%"TAP"
"1","(-3475,4100)","0","mstr_standard","I196";
;
CDS_LIB"mstr_standard"
BODY_TYPE"PLUMBING"
HDL_TAP"TRUE";
"B \NAC \NWC"2;
"S \NAC"
BN"3"129;
%"TAP"
"1","(-3475,4150)","0","mstr_standard","I197";
;
CDS_LIB"mstr_standard"
BODY_TYPE"PLUMBING"
HDL_TAP"TRUE";
"B \NAC \NWC"2;
"S \NAC"
BN"2"131;
%"TAP"
"1","(-3475,3950)","0","mstr_standard","I199";
;
CDS_LIB"mstr_standard"
BODY_TYPE"PLUMBING"
HDL_TAP"TRUE";
"B \NAC \NWC"2;
"S \NAC"
BN"6"106;
%"TAP"
"1","(-3475,4000)","0","mstr_standard","I200";
;
CDS_LIB"mstr_standard"
BODY_TYPE"PLUMBING"
HDL_TAP"TRUE";
"B \NAC \NWC"2;
"S \NAC"
BN"5"107;
%"TAP"
"1","(-3475,4050)","0","mstr_standard","I201";
;
CDS_LIB"mstr_standard"
BODY_TYPE"PLUMBING"
HDL_TAP"TRUE";
"B \NAC \NWC"2;
"S \NAC"
BN"4"108;
%"TAP"
"1","(-3475,3900)","0","mstr_standard","I202";
;
CDS_LIB"mstr_standard"
BODY_TYPE"PLUMBING"
HDL_TAP"TRUE";
"B \NAC \NWC"2;
"S \NAC"
BN"7"105;
%"TAP"
"1","(-3475,3750)","0","mstr_standard","I203";
;
CDS_LIB"mstr_standard"
BODY_TYPE"PLUMBING"
HDL_TAP"TRUE";
"B \NAC \NWC"2;
"S \NAC"
BN"9"120;
%"TAP"
"1","(-3475,3800)","0","mstr_standard","I204";
;
CDS_LIB"mstr_standard"
BODY_TYPE"PLUMBING"
HDL_TAP"TRUE";
"B \NAC \NWC"2;
"S \NAC"
BN"8"122;
%"TAP"
"1","(-3475,3700)","0","mstr_standard","I205";
;
CDS_LIB"mstr_standard"
BODY_TYPE"PLUMBING"
HDL_TAP"TRUE";
"B \NAC \NWC"2;
"S \NAC"
BN"10"118;
%"TAP"
"1","(-3475,3600)","0","mstr_standard","I206";
;
CDS_LIB"mstr_standard"
BODY_TYPE"PLUMBING"
HDL_TAP"TRUE";
"B \NAC \NWC"2;
"S \NAC"
BN"12"116;
%"TAP"
"1","(-3475,3650)","0","mstr_standard","I207";
;
CDS_LIB"mstr_standard"
BODY_TYPE"PLUMBING"
HDL_TAP"TRUE";
"B \NAC \NWC"2;
"S \NAC"
BN"11"117;
%"TAP"
"1","(-3475,3550)","0","mstr_standard","I208";
;
CDS_LIB"mstr_standard"
BODY_TYPE"PLUMBING"
HDL_TAP"TRUE";
"B \NAC \NWC"2;
"S \NAC"
BN"13"115;
%"TAP"
"1","(-3475,3450)","0","mstr_standard","I209";
;
CDS_LIB"mstr_standard"
BODY_TYPE"PLUMBING"
HDL_TAP"TRUE";
"B \NAC \NWC"2;
"S \NAC"
BN"15"113;
%"TAP"
"1","(-3475,3500)","0","mstr_standard","I210";
;
CDS_LIB"mstr_standard"
BODY_TYPE"PLUMBING"
HDL_TAP"TRUE";
"B \NAC \NWC"2;
"S \NAC"
BN"14"114;
%"TAP"
"1","(-3475,3350)","0","mstr_standard","I211";
;
CDS_LIB"mstr_standard"
BODY_TYPE"PLUMBING"
HDL_TAP"TRUE";
"B \NAC \NWC"2;
"S \NAC"
BN"16"112;
%"TAP"
"1","(-3475,3250)","0","mstr_standard","I212";
;
CDS_LIB"mstr_standard"
BODY_TYPE"PLUMBING"
HDL_TAP"TRUE";
"B \NAC \NWC"2;
"S \NAC"
BN"18"110;
%"TAP"
"1","(-3475,3300)","0","mstr_standard","I213";
;
CDS_LIB"mstr_standard"
BODY_TYPE"PLUMBING"
HDL_TAP"TRUE";
"B \NAC \NWC"2;
"S \NAC"
BN"17"111;
%"TAP"
"1","(-3475,3200)","0","mstr_standard","I214";
;
CDS_LIB"mstr_standard"
BODY_TYPE"PLUMBING"
HDL_TAP"TRUE";
"B \NAC \NWC"2;
"S \NAC"
BN"19"109;
%"TAP"
"1","(-3475,3100)","0","mstr_standard","I215";
;
CDS_LIB"mstr_standard"
BODY_TYPE"PLUMBING"
HDL_TAP"TRUE";
"B \NAC \NWC"2;
"S \NAC"
BN"21"119;
%"TAP"
"1","(-3475,3150)","0","mstr_standard","I216";
;
CDS_LIB"mstr_standard"
BODY_TYPE"PLUMBING"
HDL_TAP"TRUE";
"B \NAC \NWC"2;
"S \NAC"
BN"20"121;
%"TAP"
"1","(-3475,3050)","0","mstr_standard","I217";
;
CDS_LIB"mstr_standard"
BODY_TYPE"PLUMBING"
HDL_TAP"TRUE";
"B \NAC \NWC"2;
"S \NAC"
BN"22"99;
%"TAP"
"1","(-3475,2900)","0","mstr_standard","I218";
;
CDS_LIB"mstr_standard"
BODY_TYPE"PLUMBING"
HDL_TAP"TRUE";
"B \NAC \NWC"2;
"S \NAC"
BN"24"97;
%"TAP"
"1","(-3475,2850)","0","mstr_standard","I219";
;
CDS_LIB"mstr_standard"
BODY_TYPE"PLUMBING"
HDL_TAP"TRUE";
"B \NAC \NWC"2;
"S \NAC"
BN"25"96;
%"TAP"
"1","(-3475,3000)","0","mstr_standard","I220";
;
CDS_LIB"mstr_standard"
BODY_TYPE"PLUMBING"
HDL_TAP"TRUE";
"B \NAC \NWC"2;
"S \NAC"
BN"23"98;
%"TAP"
"1","(-3475,2750)","0","mstr_standard","I221";
;
CDS_LIB"mstr_standard"
BODY_TYPE"PLUMBING"
HDL_TAP"TRUE";
"B \NAC \NWC"2;
"S \NAC"
BN"27"94;
%"TAP"
"1","(-3475,2700)","0","mstr_standard","I222";
;
CDS_LIB"mstr_standard"
BODY_TYPE"PLUMBING"
HDL_TAP"TRUE";
"B \NAC \NWC"2;
"S \NAC"
BN"28"93;
%"TAP"
"1","(-3475,2800)","0","mstr_standard","I223";
;
CDS_LIB"mstr_standard"
BODY_TYPE"PLUMBING"
HDL_TAP"TRUE";
"B \NAC \NWC"2;
"S \NAC"
BN"26"95;
%"TAP"
"1","(-3475,2650)","0","mstr_standard","I224";
;
CDS_LIB"mstr_standard"
BODY_TYPE"PLUMBING"
HDL_TAP"TRUE";
"B \NAC \NWC"2;
"S \NAC"
BN"29"92;
%"TAP"
"1","(-3475,2600)","0","mstr_standard","I225";
;
CDS_LIB"mstr_standard"
BODY_TYPE"PLUMBING"
HDL_TAP"TRUE";
"B \NAC \NWC"2;
"S \NAC"
BN"30"104;
%"TAP"
"1","(-3475,2400)","0","mstr_standard","I226";
;
CDS_LIB"mstr_standard"
BODY_TYPE"PLUMBING"
HDL_TAP"TRUE";
"B \NAC \NWC"3;
"S \NAC"
BN"1"90;
%"TAP"
"1","(-3475,2350)","0","mstr_standard","I227";
;
CDS_LIB"mstr_standard"
BODY_TYPE"PLUMBING"
HDL_TAP"TRUE";
"B \NAC \NWC"3;
"S \NAC"
BN"2"89;
%"TAP"
"1","(-3475,2550)","0","mstr_standard","I228";
;
CDS_LIB"mstr_standard"
BODY_TYPE"PLUMBING"
HDL_TAP"TRUE";
"B \NAC \NWC"2;
"S \NAC"
BN"31"102;
%"TAP"
"1","(-3475,2450)","0","mstr_standard","I229";
;
CDS_LIB"mstr_standard"
BODY_TYPE"PLUMBING"
HDL_TAP"TRUE";
"B \NAC \NWC"3;
"S \NAC"
BN"0"91;
%"TAP"
"1","(-3475,2200)","0","mstr_standard","I230";
;
CDS_LIB"mstr_standard"
BODY_TYPE"PLUMBING"
HDL_TAP"TRUE";
"B \NAC \NWC"3;
"S \NAC"
BN"5"103;
%"TAP"
"1","(-3475,2250)","0","mstr_standard","I231";
;
CDS_LIB"mstr_standard"
BODY_TYPE"PLUMBING"
HDL_TAP"TRUE";
"B \NAC \NWC"3;
"S \NAC"
BN"4"87;
%"TAP"
"1","(-3475,2300)","0","mstr_standard","I232";
;
CDS_LIB"mstr_standard"
BODY_TYPE"PLUMBING"
HDL_TAP"TRUE";
"B \NAC \NWC"3;
"S \NAC"
BN"3"88;
%"TAP"
"1","(-3475,2150)","0","mstr_standard","I233";
;
CDS_LIB"mstr_standard"
BODY_TYPE"PLUMBING"
HDL_TAP"TRUE";
"B \NAC \NWC"3;
"S \NAC"
BN"6"101;
%"TAP"
"1","(-3475,2100)","0","mstr_standard","I234";
;
CDS_LIB"mstr_standard"
BODY_TYPE"PLUMBING"
HDL_TAP"TRUE";
"B \NAC \NWC"3;
"S \NAC"
BN"7"100;
%"TAP"
"1","(-3475,2000)","0","mstr_standard","I236";
;
CDS_LIB"mstr_standard"
BODY_TYPE"PLUMBING"
HDL_TAP"TRUE";
"B \NAC \NWC"4;
"S \NAC"
BN"0"86;
%"TAP"
"1","(-3475,1950)","0","mstr_standard","I237";
;
CDS_LIB"mstr_standard"
BODY_TYPE"PLUMBING"
HDL_TAP"TRUE";
"B \NAC \NWC"4;
"S \NAC"
BN"1"85;
%"TAP"
"1","(-3475,1900)","0","mstr_standard","I238";
;
CDS_LIB"mstr_standard"
BODY_TYPE"PLUMBING"
HDL_TAP"TRUE";
"B \NAC \NWC"4;
"S \NAC"
BN"2"84;
%"TAP"
"1","(-3475,1850)","0","mstr_standard","I239";
;
CDS_LIB"mstr_standard"
BODY_TYPE"PLUMBING"
HDL_TAP"TRUE";
"B \NAC \NWC"4;
"S \NAC"
BN"3"83;
%"TAP"
"1","(-3475,1800)","0","mstr_standard","I240";
;
CDS_LIB"mstr_standard"
BODY_TYPE"PLUMBING"
HDL_TAP"TRUE";
"B \NAC \NWC"4;
"S \NAC"
BN"4"82;
%"TAP"
"1","(-3475,1750)","0","mstr_standard","I241";
;
CDS_LIB"mstr_standard"
BODY_TYPE"PLUMBING"
HDL_TAP"TRUE";
"B \NAC \NWC"4;
"S \NAC"
BN"5"81;
%"TAP"
"1","(-3475,1650)","0","mstr_standard","I242";
;
CDS_LIB"mstr_standard"
BODY_TYPE"PLUMBING"
HDL_TAP"TRUE";
"B \NAC \NWC"4;
"S \NAC"
BN"7"79;
%"TAP"
"1","(-3475,1700)","0","mstr_standard","I243";
;
CDS_LIB"mstr_standard"
BODY_TYPE"PLUMBING"
HDL_TAP"TRUE";
"B \NAC \NWC"4;
"S \NAC"
BN"6"80;
%"TAP"
"1","(-5900,6050)","2","mstr_standard","I244";
;
CDS_LIB"mstr_standard"
BODY_TYPE"PLUMBING"
HDL_TAP"TRUE";
"B \NAC \NWC"5;
"S \NAC"
BN"0"74;
%"TAP"
"1","(-5900,5950)","2","mstr_standard","I245";
;
CDS_LIB"mstr_standard"
BODY_TYPE"PLUMBING"
HDL_TAP"TRUE";
"B \NAC \NWC"5;
"S \NAC"
BN"1"72;
%"TAP"
"1","(-5900,5850)","2","mstr_standard","I246";
;
CDS_LIB"mstr_standard"
BODY_TYPE"PLUMBING"
HDL_TAP"TRUE";
"B \NAC \NWC"5;
"S \NAC"
BN"2"70;
%"TAP"
"1","(-5900,5650)","2","mstr_standard","I247";
;
CDS_LIB"mstr_standard"
BODY_TYPE"PLUMBING"
HDL_TAP"TRUE";
"B \NAC \NWC"5;
"S \NAC"
BN"4"66;
%"TAP"
"1","(-5900,5750)","2","mstr_standard","I248";
;
CDS_LIB"mstr_standard"
BODY_TYPE"PLUMBING"
HDL_TAP"TRUE";
"B \NAC \NWC"5;
"S \NAC"
BN"3"68;
%"TAP"
"1","(-6100,5900)","2","mstr_standard","I249";
;
CDS_LIB"mstr_standard"
BODY_TYPE"PLUMBING"
HDL_TAP"TRUE";
"B \NAC \NWC"9;
"S \NAC"
BN"1"78;
%"TAP"
"1","(-6100,6000)","2","mstr_standard","I250";
;
CDS_LIB"mstr_standard"
BODY_TYPE"PLUMBING"
HDL_TAP"TRUE";
"B \NAC \NWC"9;
"S \NAC"
BN"0"60;
%"TAP"
"1","(-6100,5800)","2","mstr_standard","I251";
;
CDS_LIB"mstr_standard"
BODY_TYPE"PLUMBING"
HDL_TAP"TRUE";
"B \NAC \NWC"9;
"S \NAC"
BN"2"77;
%"TAP"
"1","(-6100,5700)","2","mstr_standard","I252";
;
CDS_LIB"mstr_standard"
BODY_TYPE"PLUMBING"
HDL_TAP"TRUE";
"B \NAC \NWC"9;
"S \NAC"
BN"3"76;
%"TAP"
"1","(-5900,5550)","2","mstr_standard","I253";
;
CDS_LIB"mstr_standard"
BODY_TYPE"PLUMBING"
HDL_TAP"TRUE";
"B \NAC \NWC"5;
"S \NAC"
BN"5"65;
%"TAP"
"1","(-5900,5450)","2","mstr_standard","I254";
;
CDS_LIB"mstr_standard"
BODY_TYPE"PLUMBING"
HDL_TAP"TRUE";
"B \NAC \NWC"5;
"S \NAC"
BN"6"64;
%"TAP"
"1","(-5900,5250)","2","mstr_standard","I255";
;
CDS_LIB"mstr_standard"
BODY_TYPE"PLUMBING"
HDL_TAP"TRUE";
"B \NAC \NWC"5;
"S \NAC"
BN"8"62;
%"TAP"
"1","(-5900,5350)","2","mstr_standard","I256";
;
CDS_LIB"mstr_standard"
BODY_TYPE"PLUMBING"
HDL_TAP"TRUE";
"B \NAC \NWC"5;
"S \NAC"
BN"7"63;
%"TAP"
"1","(-5900,5150)","2","mstr_standard","I257";
;
CDS_LIB"mstr_standard"
BODY_TYPE"PLUMBING"
HDL_TAP"TRUE";
"B \NAC \NWC"5;
"S \NAC"
BN"9"61;
%"TAP"
"1","(-6100,5500)","2","mstr_standard","I258";
;
CDS_LIB"mstr_standard"
BODY_TYPE"PLUMBING"
HDL_TAP"TRUE";
"B \NAC \NWC"9;
"S \NAC"
BN"5"73;
%"TAP"
"1","(-6100,5600)","2","mstr_standard","I259";
;
CDS_LIB"mstr_standard"
BODY_TYPE"PLUMBING"
HDL_TAP"TRUE";
"B \NAC \NWC"9;
"S \NAC"
BN"4"75;
%"TAP"
"1","(-6100,5400)","2","mstr_standard","I260";
;
CDS_LIB"mstr_standard"
BODY_TYPE"PLUMBING"
HDL_TAP"TRUE";
"B \NAC \NWC"9;
"S \NAC"
BN"6"71;
%"TAP"
"1","(-6100,5300)","2","mstr_standard","I261";
;
CDS_LIB"mstr_standard"
BODY_TYPE"PLUMBING"
HDL_TAP"TRUE";
"B \NAC \NWC"9;
"S \NAC"
BN"7"69;
%"TAP"
"1","(-6100,5200)","2","mstr_standard","I262";
;
CDS_LIB"mstr_standard"
BODY_TYPE"PLUMBING"
HDL_TAP"TRUE";
"B \NAC \NWC"9;
"S \NAC"
BN"8"67;
%"TAP"
"1","(-5900,5000)","2","mstr_standard","I263";
;
CDS_LIB"mstr_standard"
BODY_TYPE"PLUMBING"
HDL_TAP"TRUE";
"B \NAC \NWC"6;
"S \NAC"
BN"0"52;
%"TAP"
"1","(-5900,4900)","2","mstr_standard","I264";
;
CDS_LIB"mstr_standard"
BODY_TYPE"PLUMBING"
HDL_TAP"TRUE";
"B \NAC \NWC"6;
"S \NAC"
BN"1"50;
%"TAP"
"1","(-5900,4800)","2","mstr_standard","I265";
;
CDS_LIB"mstr_standard"
BODY_TYPE"PLUMBING"
HDL_TAP"TRUE";
"B \NAC \NWC"6;
"S \NAC"
BN"2"48;
%"TAP"
"1","(-5900,4700)","2","mstr_standard","I266";
;
CDS_LIB"mstr_standard"
BODY_TYPE"PLUMBING"
HDL_TAP"TRUE";
"B \NAC \NWC"6;
"S \NAC"
BN"3"46;
%"TAP"
"1","(-6100,5100)","2","mstr_standard","I267";
;
CDS_LIB"mstr_standard"
BODY_TYPE"PLUMBING"
HDL_TAP"TRUE";
"B \NAC \NWC"9;
"S \NAC"
BN"9"54;
%"TAP"
"1","(-6100,4950)","2","mstr_standard","I268";
;
CDS_LIB"mstr_standard"
BODY_TYPE"PLUMBING"
HDL_TAP"TRUE";
"B \NAC \NWC"10;
"S \NAC"
BN"0"58;
%"TAP"
"1","(-6100,4850)","2","mstr_standard","I269";
;
CDS_LIB"mstr_standard"
BODY_TYPE"PLUMBING"
HDL_TAP"TRUE";
"B \NAC \NWC"10;
"S \NAC"
BN"1"57;
%"TAP"
"1","(-6100,4750)","2","mstr_standard","I270";
;
CDS_LIB"mstr_standard"
BODY_TYPE"PLUMBING"
HDL_TAP"TRUE";
"B \NAC \NWC"10;
"S \NAC"
BN"2"56;
%"TAP"
"1","(-6100,4650)","2","mstr_standard","I271";
;
CDS_LIB"mstr_standard"
BODY_TYPE"PLUMBING"
HDL_TAP"TRUE";
"B \NAC \NWC"10;
"S \NAC"
BN"3"55;
%"TAP"
"1","(-5900,4500)","2","mstr_standard","I272";
;
CDS_LIB"mstr_standard"
BODY_TYPE"PLUMBING"
HDL_TAP"TRUE";
"B \NAC \NWC"6;
"S \NAC"
BN"5"43;
%"TAP"
"1","(-5900,4600)","2","mstr_standard","I273";
;
CDS_LIB"mstr_standard"
BODY_TYPE"PLUMBING"
HDL_TAP"TRUE";
"B \NAC \NWC"6;
"S \NAC"
BN"4"44;
%"TAP"
"1","(-5900,4400)","2","mstr_standard","I274";
;
CDS_LIB"mstr_standard"
BODY_TYPE"PLUMBING"
HDL_TAP"TRUE";
"B \NAC \NWC"6;
"S \NAC"
BN"6"42;
%"TAP"
"1","(-5900,4300)","2","mstr_standard","I275";
;
CDS_LIB"mstr_standard"
BODY_TYPE"PLUMBING"
HDL_TAP"TRUE";
"B \NAC \NWC"6;
"S \NAC"
BN"7"41;
%"TAP"
"1","(-5900,4100)","2","mstr_standard","I276";
;
CDS_LIB"mstr_standard"
BODY_TYPE"PLUMBING"
HDL_TAP"TRUE";
"B \NAC \NWC"6;
"S \NAC"
BN"9"40;
%"TAP"
"1","(-5900,4200)","2","mstr_standard","I277";
;
CDS_LIB"mstr_standard"
BODY_TYPE"PLUMBING"
HDL_TAP"TRUE";
"B \NAC \NWC"6;
"S \NAC"
BN"8"59;
%"TAP"
"1","(-6100,4450)","2","mstr_standard","I278";
;
CDS_LIB"mstr_standard"
BODY_TYPE"PLUMBING"
HDL_TAP"TRUE";
"B \NAC \NWC"10;
"S \NAC"
BN"5"51;
%"TAP"
"1","(-6100,4550)","2","mstr_standard","I279";
;
CDS_LIB"mstr_standard"
BODY_TYPE"PLUMBING"
HDL_TAP"TRUE";
"B \NAC \NWC"10;
"S \NAC"
BN"4"53;
%"TAP"
"1","(-6100,4350)","2","mstr_standard","I280";
;
CDS_LIB"mstr_standard"
BODY_TYPE"PLUMBING"
HDL_TAP"TRUE";
"B \NAC \NWC"10;
"S \NAC"
BN"6"49;
%"TAP"
"1","(-6100,4250)","2","mstr_standard","I281";
;
CDS_LIB"mstr_standard"
BODY_TYPE"PLUMBING"
HDL_TAP"TRUE";
"B \NAC \NWC"10;
"S \NAC"
BN"7"47;
%"TAP"
"1","(-6100,4150)","2","mstr_standard","I282";
;
CDS_LIB"mstr_standard"
BODY_TYPE"PLUMBING"
HDL_TAP"TRUE";
"B \NAC \NWC"10;
"S \NAC"
BN"8"45;
%"TAP"
"1","(-6100,4050)","2","mstr_standard","I287";
;
CDS_LIB"mstr_standard"
BODY_TYPE"PLUMBING"
HDL_TAP"TRUE";
"B \NAC \NWC"10;
"S \NAC"
BN"9"26;
%"TAP"
"1","(-6100,3850)","2","mstr_standard","I288";
;
CDS_LIB"mstr_standard"
BODY_TYPE"PLUMBING"
HDL_TAP"TRUE";
"B \NAC \NWC"7;
"S \NAC"
BN"1"37;
%"TAP"
"1","(-6100,3900)","2","mstr_standard","I289";
;
CDS_LIB"mstr_standard"
BODY_TYPE"PLUMBING"
HDL_TAP"TRUE";
"B \NAC \NWC"7;
"S \NAC"
BN"0"39;
%"TAP"
"1","(-6100,3750)","2","mstr_standard","I290";
;
CDS_LIB"mstr_standard"
BODY_TYPE"PLUMBING"
HDL_TAP"TRUE";
"B \NAC \NWC"7;
"S \NAC"
BN"3"33;
%"TAP"
"1","(-6100,3800)","2","mstr_standard","I291";
;
CDS_LIB"mstr_standard"
BODY_TYPE"PLUMBING"
HDL_TAP"TRUE";
"B \NAC \NWC"7;
"S \NAC"
BN"2"35;
%"TAP"
"1","(-6100,3700)","2","mstr_standard","I292";
;
CDS_LIB"mstr_standard"
BODY_TYPE"PLUMBING"
HDL_TAP"TRUE";
"B \NAC \NWC"7;
"S \NAC"
BN"4"31;
%"TAP"
"1","(-6100,3650)","2","mstr_standard","I293";
;
CDS_LIB"mstr_standard"
BODY_TYPE"PLUMBING"
HDL_TAP"TRUE";
"B \NAC \NWC"7;
"S \NAC"
BN"5"29;
%"TAP"
"1","(-6100,3600)","2","mstr_standard","I294";
;
CDS_LIB"mstr_standard"
BODY_TYPE"PLUMBING"
HDL_TAP"TRUE";
"B \NAC \NWC"7;
"S \NAC"
BN"6"27;
%"TAP"
"1","(-6100,3400)","2","mstr_standard","I295";
;
CDS_LIB"mstr_standard"
BODY_TYPE"PLUMBING"
HDL_TAP"TRUE";
"B \NAC \NWC"8;
"S \NAC"
BN"2"34;
%"TAP"
"1","(-6100,3450)","2","mstr_standard","I296";
;
CDS_LIB"mstr_standard"
BODY_TYPE"PLUMBING"
HDL_TAP"TRUE";
"B \NAC \NWC"8;
"S \NAC"
BN"1"36;
%"TAP"
"1","(-6100,3500)","2","mstr_standard","I297";
;
CDS_LIB"mstr_standard"
BODY_TYPE"PLUMBING"
HDL_TAP"TRUE";
"B \NAC \NWC"8;
"S \NAC"
BN"0"38;
%"TAP"
"1","(-6100,3350)","2","mstr_standard","I298";
;
CDS_LIB"mstr_standard"
BODY_TYPE"PLUMBING"
HDL_TAP"TRUE";
"B \NAC \NWC"8;
"S \NAC"
BN"3"32;
%"TAP"
"1","(-6100,3300)","2","mstr_standard","I299";
;
CDS_LIB"mstr_standard"
BODY_TYPE"PLUMBING"
HDL_TAP"TRUE";
"B \NAC \NWC"8;
"S \NAC"
BN"4"30;
%"TAP"
"1","(-6100,3250)","2","mstr_standard","I300";
;
CDS_LIB"mstr_standard"
BODY_TYPE"PLUMBING"
HDL_TAP"TRUE";
"B \NAC \NWC"8;
"S \NAC"
BN"5"28;
%"TAP"
"1","(-6100,3200)","2","mstr_standard","I301";
;
CDS_LIB"mstr_standard"
BODY_TYPE"PLUMBING"
HDL_TAP"TRUE";
"B \NAC \NWC"8;
"S \NAC"
BN"6"25;
%"Q_RES"
"1","(-6775,2200)","0","pure_quanta","I313";
;
LOCATION"R502"
$SEC"1"
CDS_SEC"1"
TOLERANCE"1%"
VALUE"15   "
PART_NUMBER"CS01502FB11"
PACK_TYPE"0402LF"
CDS_LIB"pure_quanta"
WATTAGE"1/16W"
MATERIAL"CHIP";
"B"
$PN"2"13;
"A"
$PN"1"11;
END.
